(kicad_pcb
	(version 20260206)
	(generator "pcbnew")
	(generator_version "10.0")
	(general
		(thickness 1.21888)
		(legacy_teardrops no)
	)
	(paper "A4")
	(title_block
		(title "timecard-proto-v0 — Timingcard_PCB.PcbDoc")
		(comment 1 "Time Appliance Project (Time Card) / footprints 85-91 of 167")
	)
	(layers
		(0 "F.Cu" signal "TOP")
		(4 "In1.Cu" signal "SGND")
		(6 "In2.Cu" signal "IN1")
		(8 "In3.Cu" signal "IN2")
		(10 "In4.Cu" signal "SGND1")
		(2 "B.Cu" signal "BOTTOM")
		(9 "F.Adhes" user "F.Adhesive")
		(11 "B.Adhes" user "B.Adhesive")
		(13 "F.Paste" user "Top Paste")
		(15 "B.Paste" user "Bottom Paste")
		(5 "F.SilkS" user "Top Overlay")
		(7 "B.SilkS" user "Bottom Overlay")
		(1 "F.Mask" user "Top Solder")
		(3 "B.Mask" user "Bottom Solder")
		(17 "Dwgs.User" user "User.Drawings")
		(19 "Cmts.User" user "User.Comments")
		(21 "Eco1.User" user "User.Eco1")
		(23 "Eco2.User" user "User.Eco2")
		(25 "Edge.Cuts" user)
		(27 "Margin" user)
		(31 "F.CrtYd" user "Top Courtyard")
		(29 "B.CrtYd" user "Bottom Courtyard")
		(35 "F.Fab" user "Top Component Center")
		(33 "B.Fab" user "Bottom Component Center")
	)
	(footprint "Passives:SODFL370X135-2N"
		(layer "F.Cu")
		(at 209.868595 66.5716)
		(property "Reference" "D1"
			(at 3.413345 0.407 90)
			(unlocked yes)
			(layer "F.SilkS")
			(effects
				(font
					(size 0.762 0.762)
					(thickness 0.2286)
				)
				(justify left bottom)
			)
		)
		(property "Value" "DFLZ39-TP"
			(at -2.0955 3.62839 0)
			(unlocked yes)
			(layer "F.SilkS")
			(hide yes)
			(effects
				(font
					(size 1.524 1.524)
					(thickness 0.254)
				)
				(justify left bottom)
			)
		)
		(sheetname "POWER")
		(sheetfile "POWER.kicad_sch")
		(duplicate_pad_numbers_are_jumpers no)
		(fp_line
			(start -1.55 -0.95)
			(end 1.55 -0.95)
			(stroke
				(width 0.2)
				(type solid)
			)
			(layer "F.SilkS")
		)
		(fp_line
			(start -1.55 -0.825)
			(end -1.55 -0.95)
			(stroke
				(width 0.2)
				(type solid)
			)
			(layer "F.SilkS")
		)
		(fp_line
			(start -1.55 0.95)
			(end -1.55 0.825)
			(stroke
				(width 0.2)
				(type solid)
			)
			(layer "F.SilkS")
		)
		(fp_line
			(start -1.55 0.95)
			(end 1.55 0.95)
			(stroke
				(width 0.2)
				(type solid)
			)
			(layer "F.SilkS")
		)
		(fp_line
			(start 1.55 -0.825)
			(end 1.55 -0.95)
			(stroke
				(width 0.2)
				(type solid)
			)
			(layer "F.SilkS")
		)
		(fp_line
			(start 1.55 0.95)
			(end 1.55 0.825)
			(stroke
				(width 0.2)
				(type solid)
			)
			(layer "F.SilkS")
		)
		(fp_circle
			(center -2.05 -0.825)
			(end -2.05 -0.875)
			(stroke
				(width 0.1)
				(type solid)
			)
			(fill no)
			(layer "F.SilkS")
		)
		(pad "1" smd rect
			(at -1.825 0 90)
			(size 1.05 0.65)
			(layers "F.Cu" "F.Mask" "F.Paste")
			(net "NetD1_1")
		)
		(pad "2" smd rect
			(at 1.825 0 90)
			(size 1.05 0.65)
			(layers "F.Cu" "F.Mask" "F.Paste")
			(net "NetD1_2")
		)
	)
	(footprint "Passives:SOT65P210X110-3N"
		(layer "F.Cu")
		(at 127.572595 66.4446 -90)
		(property "Reference" "D6"
			(at -2.865945 0.36799 0)
			(unlocked yes)
			(layer "F.SilkS")
			(effects
				(font
					(size 0.762 0.762)
					(thickness 0.2286)
				)
				(justify left bottom)
			)
		)
		(property "Value" "BAT54SW"
			(at 3.88239 1.5875 0)
			(unlocked yes)
			(layer "F.SilkS")
			(hide yes)
			(effects
				(font
					(size 1.524 1.524)
					(thickness 0.254)
				)
				(justify left bottom)
			)
		)
		(sheetname "PCIe_JTAG")
		(sheetfile "PCIe_JTAG.kicad_sch")
		(duplicate_pad_numbers_are_jumpers no)
		(fp_line
			(start 0.675 1.1)
			(end -0.325 1.1)
			(stroke
				(width 0.2)
				(type solid)
			)
			(layer "F.SilkS")
		)
		(fp_line
			(start 0.675 1.1)
			(end 0.675 0.65)
			(stroke
				(width 0.2)
				(type solid)
			)
			(layer "F.SilkS")
		)
		(fp_line
			(start 0.675 -0.65)
			(end 0.675 -1.1)
			(stroke
				(width 0.2)
				(type solid)
			)
			(layer "F.SilkS")
		)
		(fp_line
			(start 0.675 -1.1)
			(end -0.325 -1.1)
			(stroke
				(width 0.2)
				(type solid)
			)
			(layer "F.SilkS")
		)
		(fp_circle
			(center -1.125 -1.45)
			(end -1.25 -1.45)
			(stroke
				(width 0.25)
				(type solid)
			)
			(fill no)
			(layer "F.SilkS")
		)
		(pad "1" smd rect
			(at -1.125 -0.65)
			(size 0.5 0.9)
			(layers "F.Cu" "F.Mask" "F.Paste")
			(net "GND")
		)
		(pad "2" smd rect
			(at -1.125 0.65)
			(size 0.5 0.9)
			(layers "F.Cu" "F.Mask" "F.Paste")
			(net "+3.3V")
		)
		(pad "3" smd rect
			(at 1.125 0)
			(size 0.5 0.9)
			(layers "F.Cu" "F.Mask" "F.Paste")
			(net "FPGA_TDO")
		)
	)
	(footprint "Vault:CAPC1608X87X45ML20T05"
		(layer "F.Cu")
		(at 162.878595 82.8276 -90)
		(property "Reference" "C77"
			(at -3.249 1.771655 90)
			(unlocked yes)
			(layer "F.SilkS")
			(effects
				(font
					(size 0.762 0.762)
					(thickness 0.2286)
				)
				(justify left bottom)
			)
		)
		(property "Value" "0.1uF"
			(at 3.47599 0.2921 0)
			(unlocked yes)
			(layer "F.SilkS")
			(hide yes)
			(effects
				(font
					(size 1.524 1.524)
					(thickness 0.254)
				)
				(justify left bottom)
			)
		)
		(sheetname "MAC")
		(sheetfile "MAC.kicad_sch")
		(duplicate_pad_numbers_are_jumpers no)
		(pad "1" smd rect
			(at -0.7 0)
			(size 1.1 1.05)
			(layers "F.Cu" "F.Mask" "F.Paste")
			(net "GND")
		)
		(pad "2" smd rect
			(at 0.7 0)
			(size 1.1 1.05)
			(layers "F.Cu" "F.Mask" "F.Paste")
			(net "+3.3V_CLEAN")
		)
	)
	(footprint "Vault:CAPC1608X87X45ML20T05"
		(layer "F.Cu")
		(at 233.109595 107.3386 180)
		(property "Reference" "C19"
			(at 1.046 1.141655 0)
			(unlocked yes)
			(layer "F.SilkS")
			(effects
				(font
					(size 0.762 0.762)
					(thickness 0.2286)
				)
				(justify left bottom)
			)
		)
		(property "Value" "0.1uF"
			(at 3.9751 -3.95859 0)
			(unlocked yes)
			(layer "F.SilkS")
			(hide yes)
			(effects
				(font
					(size 1.524 1.524)
					(thickness 0.254)
				)
				(justify left bottom)
			)
		)
		(sheetname "POWER")
		(sheetfile "POWER.kicad_sch")
		(duplicate_pad_numbers_are_jumpers no)
		(pad "1" smd rect
			(at -0.7 0 270)
			(size 1.1 1.05)
			(layers "F.Cu" "F.Mask" "F.Paste")
			(net "GND")
		)
		(pad "2" smd rect
			(at 0.7 0 270)
			(size 1.1 1.05)
			(layers "F.Cu" "F.Mask" "F.Paste")
			(net "NetC19_2")
		)
	)
	(footprint "Vault:CAPC1608X87X45ML20T05"
		(layer "F.Cu")
		(at 227.648595 116.8636)
		(property "Reference" "C17"
			(at 1.74 0.708345 0)
			(unlocked yes)
			(layer "F.SilkS")
			(effects
				(font
					(size 0.762 0.762)
					(thickness 0.2286)
				)
				(justify left bottom)
			)
		)
		(property "Value" "0.1uF"
			(at 1.6129 8.42899 0)
			(unlocked yes)
			(layer "F.SilkS")
			(hide yes)
			(effects
				(font
					(size 1.524 1.524)
					(thickness 0.254)
				)
				(justify left bottom)
			)
		)
		(sheetname "POWER")
		(sheetfile "POWER.kicad_sch")
		(duplicate_pad_numbers_are_jumpers no)
		(pad "1" smd rect
			(at -0.7 0 90)
			(size 1.1 1.05)
			(layers "F.Cu" "F.Mask" "F.Paste")
			(net "GND")
		)
		(pad "2" smd rect
			(at 0.7 0 90)
			(size 1.1 1.05)
			(layers "F.Cu" "F.Mask" "F.Paste")
			(net "+5.0V")
		)
	)
	(footprint "Miscellaneous:SIT5721"
		(layer "F.Cu")
		(at 146.149595 76.7406 -90)
		(property "Reference" "U11"
			(at -2.189145 7.41965 0)
			(unlocked yes)
			(layer "F.SilkS")
			(effects
				(font
					(size 0.762 0.762)
					(thickness 0.2286)
				)
				(justify left bottom)
			)
		)
		(property "Value" "SiT5721AI-KWA33-T-10.000000"
			(at 5.60959 1.61298 0)
			(unlocked yes)
			(layer "F.SilkS")
			(hide yes)
			(effects
				(font
					(size 1.524 1.524)
					(thickness 0.254)
				)
				(justify left bottom)
			)
		)
		(sheetname "MAC")
		(sheetfile "MAC.kicad_sch")
		(duplicate_pad_numbers_are_jumpers no)
		(fp_line
			(start -3.5 4.5)
			(end -3.5 3.5)
			(stroke
				(width 0.2032)
				(type solid)
			)
			(layer "F.SilkS")
		)
		(fp_line
			(start -2.5 4.5)
			(end -3.5 4.5)
			(stroke
				(width 0.2032)
				(type solid)
			)
			(layer "F.SilkS")
		)
		(fp_line
			(start 3.5 4.5)
			(end 2.5 4.5)
			(stroke
				(width 0.2032)
				(type solid)
			)
			(layer "F.SilkS")
		)
		(fp_line
			(start 3.5 4.5)
			(end 3.5 3.5)
			(stroke
				(width 0.2032)
				(type solid)
			)
			(layer "F.SilkS")
		)
		(fp_line
			(start -3.5 -1.45426)
			(end -3.5 -4.5)
			(stroke
				(width 0.2032)
				(type solid)
			)
			(layer "F.SilkS")
		)
		(fp_line
			(start 3.5 -3.5)
			(end 3.5 -4.5)
			(stroke
				(width 0.2032)
				(type solid)
			)
			(layer "F.SilkS")
		)
		(fp_line
			(start -0.66154 -4.5)
			(end -3.5 -4.5)
			(stroke
				(width 0.2032)
				(type solid)
			)
			(layer "F.SilkS")
		)
		(fp_line
			(start 3.5 -4.5)
			(end 2.5 -4.5)
			(stroke
				(width 0.2032)
				(type solid)
			)
			(layer "F.SilkS")
		)
		(pad "1" smd rect
			(at -2.15 -3 270)
			(size 2.3 1)
			(layers "F.Cu" "F.Mask" "F.Paste")
		)
		(pad "2" smd rect
			(at -2.4 -1.5 270)
			(size 1.8 1)
			(layers "F.Cu" "F.Mask" "F.Paste")
			(net "5721_STATUS")
		)
		(pad "3" smd rect
			(at -2.4 0 270)
			(size 1.8 1)
			(layers "F.Cu" "F.Mask" "F.Paste")
			(net "SCL")
		)
		(pad "4" smd rect
			(at -2.4 1.5 270)
			(size 1.8 1)
			(layers "F.Cu" "F.Mask" "F.Paste")
			(net "SDA")
		)
		(pad "5" smd rect
			(at -2.4 3 90)
			(size 1.8 1)
			(layers "F.Cu" "F.Mask" "F.Paste")
			(net "GND")
		)
		(pad "6" smd rect
			(at 2.4 3 270)
			(size 1.8 1)
			(layers "F.Cu" "F.Mask" "F.Paste")
			(net "DCXO2")
		)
		(pad "7" smd rect
			(at 2.4 1.5 270)
			(size 1.8 1)
			(layers "F.Cu" "F.Mask" "F.Paste")
		)
		(pad "8" smd rect
			(at 2.4 0 270)
			(size 1.8 1)
			(layers "F.Cu" "F.Mask" "F.Paste")
		)
		(pad "9" smd rect
			(at 2.4 -1.5 270)
			(size 1.8 1)
			(layers "F.Cu" "F.Mask" "F.Paste")
		)
		(pad "10" smd rect
			(at 2.4 -3 90)
			(size 1.8 1)
			(layers "F.Cu" "F.Mask" "F.Paste")
			(net "+3.3V_CLEAN")
		)
	)
	(footprint "Miscellaneous Devices:J1-0603"
		(layer "F.Cu")
		(at 82.113595 116.2036 180)
		(property "Reference" "R14"
			(at -2.829 -0.001931 0)
			(unlocked yes)
			(layer "F.SilkS")
			(effects
				(font
					(size 0.762 0.762)
					(thickness 0.254)
				)
			)
		)
		(property "Value" "MACPPSO"
			(at -4.73554 -2.835402 0)
			(unlocked yes)
			(layer "F.SilkS")
			(hide yes)
			(effects
				(font
					(size 1.524 1.524)
					(thickness 0.254)
				)
			)
		)
		(sheetname "USER_IO")
		(sheetfile "USER_IO.kicad_sch")
		(duplicate_pad_numbers_are_jumpers no)
		(fp_line
			(start 0.2 0.35)
			(end -0.2 0.35)
			(stroke
				(width 0.2)
				(type solid)
			)
			(layer "F.SilkS")
		)
		(fp_line
			(start 0.2 -0.35)
			(end -0.2 -0.35)
			(stroke
				(width 0.2)
				(type solid)
			)
			(layer "F.SilkS")
		)
		(pad "1" smd rect
			(at -0.75 0 270)
			(size 0.9 0.7)
			(layers "F.Cu" "F.Mask" "F.Paste")
			(net "MAC_PPS_OUT+")
		)
		(pad "2" smd rect
			(at 0.75 0 270)
			(size 0.9 0.7)
			(layers "F.Cu" "F.Mask" "F.Paste")
			(net "ANT2")
		)
	)
)
